(kicad_pcb
	(version 20260206)
	(generator "pcbnew")
	(generator_version "10.0")
	(general
		(thickness 1.6)
		(legacy_teardrops no)
	)
	(paper "A4")
	(title_block
		(title "panther-plus-userver — 13130-1b_20150205.brd")
		(comment 1 "Honey Badger (Wiwynn) / footprints 505-511 of 1509")
	)
	(layers
		(0 "F.Cu" signal "TOP")
		(4 "In1.Cu" signal "L2")
		(6 "In2.Cu" signal "L3")
		(8 "In3.Cu" signal "L4")
		(10 "In4.Cu" signal "L5")
		(12 "In5.Cu" signal "L6")
		(14 "In6.Cu" signal "L7")
		(16 "In7.Cu" signal "L8")
		(18 "In8.Cu" signal "L9")
		(20 "In9.Cu" signal "L10")
		(22 "In10.Cu" signal "L11")
		(2 "B.Cu" signal "BOTTOM")
		(9 "F.Adhes" user "F.Adhesive")
		(11 "B.Adhes" user "B.Adhesive")
		(13 "F.Paste" user "Package Geometry/Pastemask Top")
		(15 "B.Paste" user "Package Geometry/Pastemask Bottom")
		(5 "F.SilkS" user "Ref Des/Silkscreen Top")
		(7 "B.SilkS" user "Ref Des/Silkscreen Bottom")
		(1 "F.Mask" user "Board Geometry/Soldermask Top")
		(3 "B.Mask" user "Board Geometry/Soldermask Bottom")
		(17 "Dwgs.User" user "User.Drawings")
		(19 "Cmts.User" user "User.Comments")
		(21 "Eco1.User" user "User.Eco1")
		(23 "Eco2.User" user "User.Eco2")
		(25 "Edge.Cuts" user "Board Geometry/Outline")
		(27 "Margin" user)
		(31 "F.CrtYd" user "Package Geometry/Place Bound Top")
		(29 "B.CrtYd" user "Package Geometry/Place Bound Bottom")
		(35 "F.Fab" user "Ref Des/Assembly Top")
		(33 "B.Fab" user "Ref Des/Assembly Bottom")
	)
	(footprint ""
		(layer "F.Cu")
		(at 25.654 -62.5094 180)
		(property "Reference" "PR25"
			(at 0 0 180)
			(layer "F.SilkS")
			(hide yes)
			(effects
				(font
					(size 1.27 1.27)
				)
			)
		)
		(property "Value" "0R3J-0-U-GP"
			(at -0.0254 -2.0193 180)
			(unlocked yes)
			(layer "F.Fab")
			(hide yes)
			(effects
				(font
					(size 1.016 1.016)
					(thickness 0.1524)
				)
			)
		)
		(property "Device Type" "R603H22"
			(at -0.0254 -3.5433 180)
			(unlocked yes)
			(layer "F.Fab")
			(hide yes)
			(effects
				(font
					(size 1.016 1.016)
					(thickness 0.1524)
				)
			)
		)
		(duplicate_pad_numbers_are_jumpers no)
		(fp_line
			(start 0.4318 0)
			(end 0.2032 0)
			(stroke
				(width 0.2032)
				(type default)
			)
			(layer "F.SilkS")
		)
		(fp_line
			(start -0.2032 0)
			(end -0.4191 0)
			(stroke
				(width 0.2032)
				(type default)
			)
			(layer "F.SilkS")
		)
		(fp_rect
			(start -0.635 1.1811)
			(end 0.635 -1.1811)
			(stroke
				(width 0)
				(type default)
			)
			(fill no)
			(layer "F.CrtYd")
		)
		(fp_rect
			(start -0.635 1.1811)
			(end 0.635 -1.1811)
			(stroke
				(width 0)
				(type default)
			)
			(fill no)
			(layer "F.Fab")
		)
		(pad "1" smd custom
			(at 0 -0.6604 180)
			(size 0.19685 0.19685)
			(layers "F.Cu" "F.Mask" "F.Paste")
			(net "VR_PVNN_GL")
			(options
				(clearance outline)
				(anchor circle)
			)
			(primitives
				(gr_poly
					(pts
						(arc
							(start 0.508 -0.2921)
							(mid 0.478242 -0.363942)
							(end 0.4064 -0.3937)
						)
						(arc
							(start -0.4064 -0.3937)
							(mid -0.478242 -0.363942)
							(end -0.508 -0.2921)
						)
						(arc
							(start -0.508 0.2921)
							(mid -0.478242 0.363942)
							(end -0.4064 0.3937)
						)
						(arc
							(start 0.4064 0.3937)
							(mid 0.478242 0.363942)
							(end 0.508 0.2921)
						)
					)
					(width 0)
					(fill yes)
				)
			)
		)
		(pad "2" smd custom
			(at 0 0.6604 180)
			(size 0.19685 0.19685)
			(layers "F.Cu" "F.Mask" "F.Paste")
			(net "VR_PVNN_LH_R")
			(options
				(clearance outline)
				(anchor circle)
			)
			(primitives
				(gr_poly
					(pts
						(arc
							(start 0.508 -0.2921)
							(mid 0.478242 -0.363942)
							(end 0.4064 -0.3937)
						)
						(arc
							(start -0.4064 -0.3937)
							(mid -0.478242 -0.363942)
							(end -0.508 -0.2921)
						)
						(arc
							(start -0.508 0.2921)
							(mid -0.478242 0.363942)
							(end -0.4064 0.3937)
						)
						(arc
							(start 0.4064 0.3937)
							(mid 0.478242 0.363942)
							(end 0.508 0.2921)
						)
					)
					(width 0)
					(fill yes)
				)
			)
		)
	)
	(footprint ""
		(layer "F.Cu")
		(at 48.5902 -34.925 180)
		(property "Reference" "R115"
			(at 0 0 180)
			(layer "F.SilkS")
			(hide yes)
			(effects
				(font
					(size 1.27 1.27)
				)
			)
		)
		(property "Value" "33R2F-3-GP"
			(at 0.064008 -3.993896 180)
			(unlocked yes)
			(layer "F.Fab")
			(hide yes)
			(effects
				(font
					(size 1.016 1.016)
					(thickness 0.1524)
				)
			)
		)
		(property "Device Type" "R402H16"
			(at 0.064008 -5.517896 180)
			(unlocked yes)
			(layer "F.Fab")
			(hide yes)
			(effects
				(font
					(size 1.016 1.016)
					(thickness 0.1524)
				)
			)
		)
		(duplicate_pad_numbers_are_jumpers no)
		(fp_rect
			(start -0.381 0.8382)
			(end 0.381 -0.8382)
			(stroke
				(width 0)
				(type default)
			)
			(fill no)
			(layer "F.CrtYd")
		)
		(fp_rect
			(start -0.381 0.8382)
			(end 0.381 -0.8382)
			(stroke
				(width 0)
				(type default)
			)
			(fill no)
			(layer "F.Fab")
		)
		(pad "1" smd custom
			(at 0 -0.4318 180)
			(size 0.127 0.127)
			(layers "F.Cu" "F.Mask" "F.Paste")
			(net "SPI_MOSI_R_1")
			(options
				(clearance outline)
				(anchor circle)
			)
			(primitives
				(gr_poly
					(pts
						(arc
							(start -0.2032 -0.2794)
							(mid -0.239121 -0.264521)
							(end -0.254 -0.2286)
						)
						(arc
							(start -0.254 0.2286)
							(mid -0.239121 0.264521)
							(end -0.2032 0.2794)
						)
						(arc
							(start 0.2032 0.2794)
							(mid 0.239121 0.264521)
							(end 0.254 0.2286)
						)
						(arc
							(start 0.254 -0.2286)
							(mid 0.239121 -0.264521)
							(end 0.2032 -0.2794)
						)
					)
					(width 0)
					(fill yes)
				)
			)
		)
		(pad "2" smd custom
			(at 0 0.4318 180)
			(size 0.127 0.127)
			(layers "F.Cu" "F.Mask" "F.Paste")
			(net "SPI_CPU_MOSI")
			(options
				(clearance outline)
				(anchor circle)
			)
			(primitives
				(gr_poly
					(pts
						(arc
							(start -0.2032 -0.2794)
							(mid -0.239121 -0.264521)
							(end -0.254 -0.2286)
						)
						(arc
							(start -0.254 0.2286)
							(mid -0.239121 0.264521)
							(end -0.2032 0.2794)
						)
						(arc
							(start 0.2032 0.2794)
							(mid 0.239121 0.264521)
							(end 0.254 0.2286)
						)
						(arc
							(start 0.254 -0.2286)
							(mid 0.239121 -0.264521)
							(end 0.2032 -0.2794)
						)
					)
					(width 0)
					(fill yes)
				)
			)
		)
	)
	(footprint ""
		(layer "F.Cu")
		(at 16.1544 -43.6626 -90)
		(property "Reference" "PR197"
			(at 0 0 270)
			(layer "F.SilkS")
			(hide yes)
			(effects
				(font
					(size 1.27 1.27)
				)
			)
		)
		(property "Value" "3D01R5F-GP"
			(at 0 -4.9022 270)
			(unlocked yes)
			(layer "F.Fab")
			(hide yes)
			(effects
				(font
					(size 1.016 1.016)
					(thickness 0.1524)
				)
			)
		)
		(property "Device Type" "R805H24"
			(at 0 -6.8072 270)
			(unlocked yes)
			(layer "F.Fab")
			(hide yes)
			(effects
				(font
					(size 1.016 1.016)
					(thickness 0.1524)
				)
			)
		)
		(duplicate_pad_numbers_are_jumpers no)
		(fp_line
			(start -0.2794 0)
			(end -0.6096 0)
			(stroke
				(width 0.3048)
				(type default)
			)
			(layer "F.SilkS")
		)
		(fp_line
			(start 0.6096 0)
			(end 0.2794 0)
			(stroke
				(width 0.3048)
				(type default)
			)
			(layer "F.SilkS")
		)
		(fp_poly
			(pts
				(xy -0.9017 1.4351) (xy 0.9017 1.4351) (xy 0.9017 -1.4351) (xy -0.9017 -1.4351)
			)
			(stroke
				(width 0)
				(type default)
			)
			(fill no)
			(layer "F.CrtYd")
		)
		(fp_poly
			(pts
				(xy 0.9017 1.4351) (xy 0.9017 -1.4351) (xy -0.9017 -1.4351) (xy -0.9017 1.4351)
			)
			(stroke
				(width 0)
				(type default)
			)
			(fill no)
			(layer "F.Fab")
		)
		(pad "1" smd rect
			(at 0 -0.8382 270)
			(size 1.5494 0.9398)
			(layers "F.Cu" "F.Mask" "F.Paste")
			(net "P3V3_STBY_SNB")
		)
		(pad "2" smd rect
			(at 0 0.8382 270)
			(size 1.5494 0.9398)
			(layers "F.Cu" "F.Mask" "F.Paste")
			(net "GND")
		)
	)
	(footprint ""
		(layer "F.Cu")
		(at 26.162 -47.879 -90)
		(property "Reference" "PR95"
			(at 0 0 270)
			(layer "F.SilkS")
			(hide yes)
			(effects
				(font
					(size 1.27 1.27)
				)
			)
		)
		(property "Value" "2K61R2F-1-GP"
			(at 1.7907 -1.1176 270)
			(unlocked yes)
			(layer "F.Fab")
			(hide yes)
			(effects
				(font
					(size 1.016 1.016)
					(thickness 0.1524)
				)
			)
		)
		(property "Device Type" "R402H16"
			(at 1.7907 -2.6416 270)
			(unlocked yes)
			(layer "F.Fab")
			(hide yes)
			(effects
				(font
					(size 1.016 1.016)
					(thickness 0.1524)
				)
			)
		)
		(duplicate_pad_numbers_are_jumpers no)
		(fp_rect
			(start -0.381 0.8382)
			(end 0.381 -0.8382)
			(stroke
				(width 0)
				(type default)
			)
			(fill no)
			(layer "F.CrtYd")
		)
		(fp_rect
			(start -0.381 0.8382)
			(end 0.381 -0.8382)
			(stroke
				(width 0)
				(type default)
			)
			(fill no)
			(layer "F.Fab")
		)
		(pad "1" smd custom
			(at 0 -0.4318 270)
			(size 0.127 0.127)
			(layers "F.Cu" "F.Mask" "F.Paste")
			(net "VR_PVCCP_ISUMP")
			(options
				(clearance outline)
				(anchor circle)
			)
			(primitives
				(gr_poly
					(pts
						(arc
							(start -0.2032 -0.2794)
							(mid -0.239121 -0.264521)
							(end -0.254 -0.2286)
						)
						(arc
							(start -0.254 0.2286)
							(mid -0.239121 0.264521)
							(end -0.2032 0.2794)
						)
						(arc
							(start 0.2032 0.2794)
							(mid 0.239121 0.264521)
							(end 0.254 0.2286)
						)
						(arc
							(start 0.254 -0.2286)
							(mid 0.239121 -0.264521)
							(end 0.2032 -0.2794)
						)
					)
					(width 0)
					(fill yes)
				)
			)
		)
		(pad "2" smd custom
			(at 0 0.4318 270)
			(size 0.127 0.127)
			(layers "F.Cu" "F.Mask" "F.Paste")
			(net "VR_PVCCP_NTC")
			(options
				(clearance outline)
				(anchor circle)
			)
			(primitives
				(gr_poly
					(pts
						(arc
							(start -0.2032 -0.2794)
							(mid -0.239121 -0.264521)
							(end -0.254 -0.2286)
						)
						(arc
							(start -0.254 0.2286)
							(mid -0.239121 0.264521)
							(end -0.2032 0.2794)
						)
						(arc
							(start 0.2032 0.2794)
							(mid 0.239121 0.264521)
							(end 0.254 0.2286)
						)
						(arc
							(start 0.254 -0.2286)
							(mid 0.239121 -0.264521)
							(end 0.2032 -0.2794)
						)
					)
					(width 0)
					(fill yes)
				)
			)
		)
	)
	(footprint ""
		(layer "F.Cu")
		(at 185.674 -39.878)
		(property "Reference" "PR122"
			(at 0 0 0)
			(layer "F.SilkS")
			(hide yes)
			(effects
				(font
					(size 1.27 1.27)
				)
			)
		)
		(property "Value" "10KR2F-2-GP"
			(at 1.7907 -1.1176 0)
			(unlocked yes)
			(layer "F.Fab")
			(hide yes)
			(effects
				(font
					(size 1.016 1.016)
					(thickness 0.1524)
				)
			)
		)
		(property "Device Type" "R402H16"
			(at 1.7907 -2.6416 0)
			(unlocked yes)
			(layer "F.Fab")
			(hide yes)
			(effects
				(font
					(size 1.016 1.016)
					(thickness 0.1524)
				)
			)
		)
		(duplicate_pad_numbers_are_jumpers no)
		(fp_rect
			(start -0.381 0.8382)
			(end 0.381 -0.8382)
			(stroke
				(width 0)
				(type default)
			)
			(fill no)
			(layer "F.CrtYd")
		)
		(fp_rect
			(start -0.381 0.8382)
			(end 0.381 -0.8382)
			(stroke
				(width 0)
				(type default)
			)
			(fill no)
			(layer "F.Fab")
		)
		(pad "1" smd custom
			(at 0 -0.4318)
			(size 0.127 0.127)
			(layers "F.Cu" "F.Mask" "F.Paste")
			(net "GND")
			(options
				(clearance outline)
				(anchor circle)
			)
			(primitives
				(gr_poly
					(pts
						(arc
							(start -0.2032 -0.2794)
							(mid -0.239121 -0.264521)
							(end -0.254 -0.2286)
						)
						(arc
							(start -0.254 0.2286)
							(mid -0.239121 0.264521)
							(end -0.2032 0.2794)
						)
						(arc
							(start 0.2032 0.2794)
							(mid 0.239121 0.264521)
							(end 0.254 0.2286)
						)
						(arc
							(start 0.254 -0.2286)
							(mid 0.239121 -0.264521)
							(end 0.2032 -0.2794)
						)
					)
					(width 0)
					(fill yes)
				)
			)
		)
		(pad "2" smd custom
			(at 0 0.4318)
			(size 0.127 0.127)
			(layers "F.Cu" "F.Mask" "F.Paste")
			(net "VR_PVDDR_A_OCP")
			(options
				(clearance outline)
				(anchor circle)
			)
			(primitives
				(gr_poly
					(pts
						(arc
							(start -0.2032 -0.2794)
							(mid -0.239121 -0.264521)
							(end -0.254 -0.2286)
						)
						(arc
							(start -0.254 0.2286)
							(mid -0.239121 0.264521)
							(end -0.2032 0.2794)
						)
						(arc
							(start 0.2032 0.2794)
							(mid 0.239121 0.264521)
							(end 0.254 0.2286)
						)
						(arc
							(start 0.254 -0.2286)
							(mid 0.239121 -0.264521)
							(end 0.2032 -0.2794)
						)
					)
					(width 0)
					(fill yes)
				)
			)
		)
	)
	(footprint ""
		(layer "F.Cu")
		(at 13.716 -56.5404)
		(property "Reference" "PR55"
			(at 0 0 0)
			(layer "F.SilkS")
			(hide yes)
			(effects
				(font
					(size 1.27 1.27)
				)
			)
		)
		(property "Value" "1K91R2F-1-GP"
			(at 1.7907 -1.1176 0)
			(unlocked yes)
			(layer "F.Fab")
			(hide yes)
			(effects
				(font
					(size 1.016 1.016)
					(thickness 0.1524)
				)
			)
		)
		(property "Device Type" "R402H16"
			(at 1.7907 -2.6416 0)
			(unlocked yes)
			(layer "F.Fab")
			(hide yes)
			(effects
				(font
					(size 1.016 1.016)
					(thickness 0.1524)
				)
			)
		)
		(duplicate_pad_numbers_are_jumpers no)
		(fp_rect
			(start -0.381 0.8382)
			(end 0.381 -0.8382)
			(stroke
				(width 0)
				(type default)
			)
			(fill no)
			(layer "F.CrtYd")
		)
		(fp_rect
			(start -0.381 0.8382)
			(end 0.381 -0.8382)
			(stroke
				(width 0)
				(type default)
			)
			(fill no)
			(layer "F.Fab")
		)
		(pad "1" smd custom
			(at 0 -0.4318)
			(size 0.127 0.127)
			(layers "F.Cu" "F.Mask" "F.Paste")
			(net "P3V3_STBY")
			(options
				(clearance outline)
				(anchor circle)
			)
			(primitives
				(gr_poly
					(pts
						(arc
							(start -0.2032 -0.2794)
							(mid -0.239121 -0.264521)
							(end -0.254 -0.2286)
						)
						(arc
							(start -0.254 0.2286)
							(mid -0.239121 0.264521)
							(end -0.2032 0.2794)
						)
						(arc
							(start 0.2032 0.2794)
							(mid 0.239121 0.264521)
							(end 0.254 0.2286)
						)
						(arc
							(start 0.254 -0.2286)
							(mid 0.239121 -0.264521)
							(end 0.2032 -0.2794)
						)
					)
					(width 0)
					(fill yes)
				)
			)
		)
		(pad "2" smd custom
			(at 0 0.4318)
			(size 0.127 0.127)
			(layers "F.Cu" "F.Mask" "F.Paste")
			(net "PWRGD_PVCCP_VNN_PG")
			(options
				(clearance outline)
				(anchor circle)
			)
			(primitives
				(gr_poly
					(pts
						(arc
							(start -0.2032 -0.2794)
							(mid -0.239121 -0.264521)
							(end -0.254 -0.2286)
						)
						(arc
							(start -0.254 0.2286)
							(mid -0.239121 0.264521)
							(end -0.2032 0.2794)
						)
						(arc
							(start 0.2032 0.2794)
							(mid 0.239121 0.264521)
							(end 0.254 0.2286)
						)
						(arc
							(start 0.254 -0.2286)
							(mid 0.239121 -0.264521)
							(end 0.2032 -0.2794)
						)
					)
					(width 0)
					(fill yes)
				)
			)
		)
	)
	(footprint ""
		(layer "F.Cu")
		(at 59.436 -25.908 -90)
		(property "Reference" "R255"
			(at 0 0 270)
			(layer "F.SilkS")
			(hide yes)
			(effects
				(font
					(size 1.27 1.27)
				)
			)
		)
		(property "Value" "1KR2F-3-GP"
			(at 0.064008 -3.993896 270)
			(unlocked yes)
			(layer "F.Fab")
			(hide yes)
			(effects
				(font
					(size 1.016 1.016)
					(thickness 0.1524)
				)
			)
		)
		(property "Device Type" "R402H16"
			(at 0.064008 -5.517896 270)
			(unlocked yes)
			(layer "F.Fab")
			(hide yes)
			(effects
				(font
					(size 1.016 1.016)
					(thickness 0.1524)
				)
			)
		)
		(duplicate_pad_numbers_are_jumpers no)
		(fp_rect
			(start -0.381 0.8382)
			(end 0.381 -0.8382)
			(stroke
				(width 0)
				(type default)
			)
			(fill no)
			(layer "F.CrtYd")
		)
		(fp_rect
			(start -0.381 0.8382)
			(end 0.381 -0.8382)
			(stroke
				(width 0)
				(type default)
			)
			(fill no)
			(layer "F.Fab")
		)
		(pad "1" smd custom
			(at 0 -0.4318 270)
			(size 0.127 0.127)
			(layers "F.Cu" "F.Mask" "F.Paste")
			(net "P3V3_STBY")
			(options
				(clearance outline)
				(anchor circle)
			)
			(primitives
				(gr_poly
					(pts
						(arc
							(start -0.2032 -0.2794)
							(mid -0.239121 -0.264521)
							(end -0.254 -0.2286)
						)
						(arc
							(start -0.254 0.2286)
							(mid -0.239121 0.264521)
							(end -0.2032 0.2794)
						)
						(arc
							(start 0.2032 0.2794)
							(mid 0.239121 0.264521)
							(end 0.254 0.2286)
						)
						(arc
							(start 0.254 -0.2286)
							(mid 0.239121 -0.264521)
							(end 0.2032 -0.2794)
						)
					)
					(width 0)
					(fill yes)
				)
			)
		)
		(pad "2" smd custom
			(at 0 0.4318 270)
			(size 0.127 0.127)
			(layers "F.Cu" "F.Mask" "F.Paste")
			(net "PWRGD_P1V8_PG")
			(options
				(clearance outline)
				(anchor circle)
			)
			(primitives
				(gr_poly
					(pts
						(arc
							(start -0.2032 -0.2794)
							(mid -0.239121 -0.264521)
							(end -0.254 -0.2286)
						)
						(arc
							(start -0.254 0.2286)
							(mid -0.239121 0.264521)
							(end -0.2032 0.2794)
						)
						(arc
							(start 0.2032 0.2794)
							(mid 0.239121 0.264521)
							(end 0.254 0.2286)
						)
						(arc
							(start 0.254 -0.2286)
							(mid 0.239121 -0.264521)
							(end 0.2032 -0.2794)
						)
					)
					(width 0)
					(fill yes)
				)
			)
		)
	)
)
